(kicad_pcb
	(version 20221018)
	(generator pcbnew)
	(general
    (thickness 1.6)
  )
	(paper "A4")
	(title_block
    (title "NUC Computer Cluster Power Breakout HW")
    (date "2023-10-18")
    (rev "1.4.3")
    (company "Antmicro Ltd.")
		(comment 9 "footprints 233-234 of 234")
	)
	(layers
    (0 "F.Cu" mixed)
    (1 "In1.Cu" power)
    (2 "In2.Cu" mixed)
    (31 "B.Cu" power)
    (32 "B.Adhes" user "B.Adhesive")
    (33 "F.Adhes" user "F.Adhesive")
    (34 "B.Paste" user)
    (35 "F.Paste" user)
    (36 "B.SilkS" user "B.Silkscreen")
    (37 "F.SilkS" user "F.Silkscreen")
    (38 "B.Mask" user)
    (39 "F.Mask" user)
    (40 "Dwgs.User" user "User.Drawings")
    (41 "Cmts.User" user "User.Comments")
    (42 "Eco1.User" user "User.Eco1")
    (43 "Eco2.User" user "User.Eco2")
    (44 "Edge.Cuts" user)
    (45 "Margin" user)
    (46 "B.CrtYd" user "B.Courtyard")
    (47 "F.CrtYd" user "F.Courtyard")
    (48 "B.Fab" user)
    (49 "F.Fab" user)
  )
	(footprint "antmicro-footprints:Vishay_PowerPAK_1212-8_Single" (layer "F.Cu")
    (at 133.65 87.25 90)
    (descr "PowerPAK 1212-8 Single")
    (tags "Vishay PowerPAK 1212-8 Single")
    (property "Author" "Antmicro")
    (property "License" "Apache-2.0")
    (property "MPN" "SI7613DN-T1-GE3")
    (property "Manufacturer" "Vishay")
    (property "Sheetfile" "power-switch.kicad_sch")
    (property "Sheetname" "Power switch 2")
    (property "ki_description" "Power MOSFET, P Channel, 20 V, 35 A, 0.0072 ohm, PowerPAK 1212, Surface Mount")
    (property "ki_keywords" "SMT, TRANSISTOR, SEMICONDUCTOR, MOSFET, PMOS")
    (attr smd)
    (fp_text reference "QA2" (at -2.85 -1 180) (layer "F.SilkS")
        (effects (font (size 0.7 0.7) (thickness 0.15)) (justify left bottom))
    )
    (fp_text value "SI7613DN-T1-GE3" (at 0 2.7 90) (layer "F.Fab")
        (effects (font (size 0.7 0.7) (thickness 0.15)) (justify left bottom))
    )
    (fp_text user "Author: Antmicro" (at -8 5.9 90) (layer "F.Fab") hide
        (effects (font (size 0.7 0.7) (thickness 0.15)) (justify left bottom))
    )
    (fp_text user "${REFERENCE}" (at -8 4.7 90) (layer "F.Fab") hide
        (effects (font (size 0.7 0.7) (thickness 0.15)) (justify left bottom))
    )
    (fp_text user "License: Apache-2.0" (at -8 7.1 90) (layer "F.Fab") hide
        (effects (font (size 0.7 0.7) (thickness 0.15)) (justify left bottom))
    )
    (fp_line (start -1.651 -1.651) (end -1.651 -1.317)
      (stroke (width 0.15) (type solid)) (layer "F.SilkS"))
    (fp_line (start -1.651 -1.651) (end 1.648 -1.651)
      (stroke (width 0.15) (type solid)) (layer "F.SilkS"))
    (fp_line (start -1.635 1.3) (end -1.635 1.634)
      (stroke (width 0.15) (type solid)) (layer "F.SilkS"))
    (fp_line (start -1.635 1.634) (end 1.634 1.634)
      (stroke (width 0.15) (type solid)) (layer "F.SilkS"))
    (fp_line (start 1.634 1.3) (end 1.634 1.634)
      (stroke (width 0.15) (type solid)) (layer "F.SilkS"))
    (fp_line (start 1.648 -1.651) (end 1.648 -1.317)
      (stroke (width 0.15) (type solid)) (layer "F.SilkS"))
    (fp_circle (center -1.9 -1.4) (end -1.85 -1.4)
      (stroke (width 0.15) (type solid)) (fill solid) (layer "F.SilkS"))
    (fp_rect (start -2 -1.8) (end 2 1.798)
      (stroke (width 0.05) (type solid)) (fill none) (layer "F.CrtYd"))
    (fp_line (start -1.6425 -1.4175) (end -1.4175 -1.6425)
      (stroke (width 0.15) (type solid)) (layer "F.Fab"))
    (fp_rect (start -1.651 -1.651) (end 1.648 1.648)
      (stroke (width 0.15) (type solid)) (fill none) (layer "F.Fab"))
    (pad "1" smd rect (at -1.436 -0.99 90) (size 0.99 0.405) (layers "F.Cu" "F.Paste" "F.Mask")
      (net 11 "VCC12V0") (pinfunction "S") (pintype "passive"))
    (pad "2" smd rect (at -1.436 -0.332 90) (size 0.99 0.405) (layers "F.Cu" "F.Paste" "F.Mask")
      (net 11 "VCC12V0") (pinfunction "S") (pintype "passive"))
    (pad "3" smd rect (at -1.436 0.33 90) (size 0.99 0.405) (layers "F.Cu" "F.Paste" "F.Mask")
      (net 11 "VCC12V0") (pinfunction "S") (pintype "passive"))
    (pad "4" smd rect (at -1.436 0.988 90) (size 0.99 0.405) (layers "F.Cu" "F.Paste" "F.Mask")
      (net 94 "Net-(QA2-G)") (pinfunction "G") (pintype "passive"))
    (pad "5" smd custom (at 0.557 0 90) (size 1.725 2.235) (layers "F.Cu" "F.Paste" "F.Mask")
      (net 22 "C_MEAS_2") (pinfunction "D") (pintype "passive") (zone_connect 2)
      (options (clearance outline) (anchor rect))
      (primitives
        (gr_poly
          (pts
            (xy 0.8625 0.1275)
            (xy 0.8625 -0.1275)
            (xy 1.3725 -0.1275)
            (xy 1.3725 -0.5325)
            (xy 0.8625 -0.5325)
            (xy 0.8625 -0.7875)
            (xy 1.3725 -0.7875)
            (xy 1.3725 -1.195)
            (xy 0.6125 -1.195)
            (xy 0.6125 1.195)
            (xy 1.3725 1.195)
            (xy 1.3725 0.7875)
            (xy 0.8625 0.7875)
            (xy 0.8625 0.5325)
            (xy 1.3725 0.5325)
            (xy 1.3725 0.1275)
          )
          (width 0) (fill yes))
      ))
  )
	(footprint "antmicro-footprints:C_0402_1005Metric" (layer "F.Cu")
    (at 170.1 123.2 -90)
    (descr "Capacitor SMD 0402")
    (tags "capacitor SMD 0402")
    (property "Author" "Antmicro")
    (property "Dielectric" "")
    (property "License" "Apache-2.0")
    (property "MPN" "CL05C180JB51PNC")
    (property "Manufacturer" "Samsung Electro-Mechanics")
    (property "Sheetfile" "ftdi-module.kicad_sch")
    (property "Sheetname" "FTDI")
    (property "Val" "18p")
    (property "Voltage" "")
    (property "ki_description" "SMD Multilayer Ceramic Capacitor, 18 pF, 50 V, 0402 [1005 Metric], ± 5%, C0G / NP0, MC")
    (property "ki_keywords" "0402, SMT, CAPACITOR, PASSIVE")
    (attr smd)
    (fp_text reference "C1" (at -0.75 -1.5 90) (layer "F.SilkS")
        (effects (font (size 0.7 0.7) (thickness 0.15)) (justify right bottom))
    )
    (fp_text value "C_18p_0402" (at -1.022927 2.155213 90) (layer "F.Fab")
        (effects (font (size 0.7 0.7) (thickness 0.15)) (justify right bottom))
    )
    (fp_text user "${REFERENCE}" (at -0.939 4.599 90) (layer "F.Fab") hide
        (effects (font (size 0.7 0.7) (thickness 0.15)) (justify right bottom))
    )
    (fp_text user "Author: Antmicro" (at -0.939 3.399 90) (layer "F.Fab") hide
        (effects (font (size 0.7 0.7) (thickness 0.15)) (justify right bottom))
    )
    (fp_text user "License: Apache-2.0" (at -0.939 5.799 90) (layer "F.Fab") hide
        (effects (font (size 0.7 0.7) (thickness 0.15)) (justify right bottom))
    )
    (fp_rect (start -0.925 -0.47) (end 0.925 0.47)
      (stroke (width 0.05) (type default)) (fill none) (layer "F.CrtYd"))
    (fp_line (start -0.494 -0.25) (end 0.504 -0.25)
      (stroke (width 0.15) (type solid)) (layer "F.Fab"))
    (fp_line (start -0.494 0.248) (end -0.494 -0.25)
      (stroke (width 0.15) (type solid)) (layer "F.Fab"))
    (fp_line (start 0.504 -0.25) (end 0.504 0.248)
      (stroke (width 0.15) (type solid)) (layer "F.Fab"))
    (fp_line (start 0.504 0.248) (end -0.494 0.248)
      (stroke (width 0.15) (type solid)) (layer "F.Fab"))
    (pad "1" smd roundrect (at -0.48 0 270) (size 0.59 0.64) (layers "F.Cu" "F.Paste" "F.Mask") (roundrect_rratio 0.25)
      (net 77 "GNDD") (pintype "passive"))
    (pad "2" smd roundrect (at 0.48 0 270) (size 0.59 0.64) (layers "F.Cu" "F.Paste" "F.Mask") (roundrect_rratio 0.25)
      (net 125 "/FTDI/OSCO") (pintype "passive"))
  )
)
